# T6G (Grand Teton) — schematic netlist excerpt (pin names and nets, part order shuffled) for the footprints in the layout excerpt that follows; sources: Cadence DE-HDL packaged netlist, KiCad conversion of 04192023_DAF0TMB3IC0_F0TG_MB_C_brd_V02_OCP.brd

U67  74CBTLV3126PW  IC  pkg TSSOP14  page 132
  \1oe\  = FB_BMC_ISOLATE
  \1a\  = NCSI_BMC_RXD1_R
  \1b\  = NCSI_OCP_SFF_RXD1
  \2oe\  = FB_BMC_ISOLATE
  \2a\  = NCSI_BMC_RXD0_R
  \2b\  = NCSI_OCP_SFF_RXD0
  GND  = GND
  \3b\  = NCSI_OCP_SFF_CRS_DV
  \3a\  = NCSI_BMC_CRS_DV_R
  \3oe\  = FB_BMC_ISOLATE
  \4b\  = OCP_SFF_ISO1_RBT_ARB_IN
  \4a\  = OCP_SFF_RBT_ARB_IN_R
  \4oe\  = FB_BMC_ISOLATE
  VCC  = P3V3_AUX

C2339  Q_CAP  0.1UF 25V 10% X7R  pkg 0402  page 182 : A = P3V3_9ZXL045_P0_VDD ; B = GND

(kicad_pcb
	(version 20260206)
	(generator "pcbnew")
	(generator_version "10.0")
	(general
		(thickness 1.6)
		(legacy_teardrops no)
	)
	(paper "A4")
	(title_block
		(title "04192023_DAF0TMB3IC0_F0TG_MB_C_brd_V02_OCP.brd")
		(comment 1 "Grand Teton / footprints 4942-4943 of 8354")
	)
	(layers
		(0 "F.Cu" signal "TOP")
		(4 "In1.Cu" signal "GND")
		(6 "In2.Cu" signal "IN1")
		(8 "In3.Cu" signal "GND1")
		(10 "In4.Cu" signal "IN2")
		(12 "In5.Cu" signal "GND2")
		(14 "In6.Cu" signal "IN3")
		(16 "In7.Cu" signal "GND3")
		(18 "In8.Cu" signal "VCC")
		(20 "In9.Cu" signal "VCC1")
		(22 "In10.Cu" signal "GND4")
		(24 "In11.Cu" signal "IN4")
		(26 "In12.Cu" signal "GND5")
		(28 "In13.Cu" signal "IN5")
		(30 "In14.Cu" signal "GND6")
		(32 "In15.Cu" signal "IN6")
		(34 "In16.Cu" signal "GND7")
		(2 "B.Cu" signal "BOTTOM")
		(9 "F.Adhes" user "F.Adhesive")
		(11 "B.Adhes" user "B.Adhesive")
		(13 "F.Paste" user "Package Geometry/Pastemask Top")
		(15 "B.Paste" user "Package Geometry/Pastemask Bottom")
		(5 "F.SilkS" user "Ref Des/Silkscreen Top")
		(7 "B.SilkS" user "Ref Des/Silkscreen Bottom")
		(1 "F.Mask" user "Board Geometry/Soldermask Top")
		(3 "B.Mask" user "Board Geometry/Soldermask Bottom")
		(17 "Dwgs.User" user "User.Drawings")
		(19 "Cmts.User" user "User.Comments")
		(21 "Eco1.User" user "User.Eco1")
		(23 "Eco2.User" user "User.Eco2")
		(25 "Edge.Cuts" user "Board Geometry/Outline")
		(27 "Margin" user)
		(31 "F.CrtYd" user "Package Geometry/Place Bound Top")
		(29 "B.CrtYd" user "Package Geometry/Place Bound Bottom")
		(35 "F.Fab" user "Ref Des/Assembly Top")
		(33 "B.Fab" user "Ref Des/Assembly Bottom")
	)
	(footprint ""
		(layer "B.Cu")
		(at 285.299912 -420.350442 90)
		(property "Reference" "C2339"
			(at 0 0 90)
			(layer "B.SilkS")
			(hide yes)
			(effects
				(font
					(size 1.27 1.27)
				)
				(justify mirror)
			)
		)
		(property "Value" ""
			(at 0 0 90)
			(layer "B.Fab")
			(effects
				(font
					(size 1.27 1.27)
				)
				(justify mirror)
			)
		)
		(duplicate_pad_numbers_are_jumpers no)
		(fp_line
			(start 0.7874 -0.4064)
			(end -0.7874 -0.4064)
			(stroke
				(width 0.1524)
				(type default)
			)
			(layer "B.SilkS")
		)
		(fp_line
			(start -0.7874 -0.4064)
			(end -0.7874 0.4064)
			(stroke
				(width 0.1524)
				(type default)
			)
			(layer "B.SilkS")
		)
		(fp_line
			(start 0.7874 0.4064)
			(end 0.7874 -0.4064)
			(stroke
				(width 0.1524)
				(type default)
			)
			(layer "B.SilkS")
		)
		(fp_line
			(start -0.7874 0.4064)
			(end 0.7874 0.4064)
			(stroke
				(width 0.1524)
				(type default)
			)
			(layer "B.SilkS")
		)
		(fp_line
			(start 0.67945 -0.305054)
			(end 0.12065 -0.305054)
			(stroke
				(width 0.1)
				(type default)
			)
			(layer "B.Fab")
		)
		(fp_line
			(start 0.12065 -0.305054)
			(end 0.12065 -0.2794)
			(stroke
				(width 0.1)
				(type default)
			)
			(layer "B.Fab")
		)
		(fp_line
			(start -0.12065 -0.3048)
			(end -0.67945 -0.3048)
			(stroke
				(width 0.1)
				(type default)
			)
			(layer "B.Fab")
		)
		(fp_line
			(start -0.67945 -0.3048)
			(end -0.67945 0.3048)
			(stroke
				(width 0.1)
				(type default)
			)
			(layer "B.Fab")
		)
		(fp_line
			(start 0.12065 -0.2794)
			(end -0.12065 -0.2794)
			(stroke
				(width 0.1)
				(type default)
			)
			(layer "B.Fab")
		)
		(fp_line
			(start -0.12065 -0.2794)
			(end -0.12065 -0.3048)
			(stroke
				(width 0.1)
				(type default)
			)
			(layer "B.Fab")
		)
		(fp_line
			(start 0.12065 0.2794)
			(end 0.12065 0.3048)
			(stroke
				(width 0.1)
				(type default)
			)
			(layer "B.Fab")
		)
		(fp_line
			(start -0.120396 0.2794)
			(end 0.12065 0.2794)
			(stroke
				(width 0.1)
				(type default)
			)
			(layer "B.Fab")
		)
		(fp_line
			(start 0.67945 0.3048)
			(end 0.67945 -0.305054)
			(stroke
				(width 0.1)
				(type default)
			)
			(layer "B.Fab")
		)
		(fp_line
			(start 0.12065 0.3048)
			(end 0.67945 0.3048)
			(stroke
				(width 0.1)
				(type default)
			)
			(layer "B.Fab")
		)
		(fp_line
			(start -0.120396 0.3048)
			(end -0.120396 0.2794)
			(stroke
				(width 0.1)
				(type default)
			)
			(layer "B.Fab")
		)
		(fp_line
			(start -0.67945 0.3048)
			(end -0.120396 0.3048)
			(stroke
				(width 0.1)
				(type default)
			)
			(layer "B.Fab")
		)
		(pad "1" smd circle
			(at 0.40005 0 270)
			(size 0 0)
			(layers "B.Cu" "B.Mask" "B.Paste")
			(net "P3V3_9ZXL045_P0_VDD")
		)
		(pad "2" smd circle
			(at -0.40005 0 270)
			(size 0 0)
			(layers "B.Cu" "B.Mask" "B.Paste")
			(net "GND")
		)
	)
	(footprint ""
		(layer "B.Cu")
		(at 197.225158 -77.192632)
		(property "Reference" "U67"
			(at 2.032 -3.27533 0)
			(unlocked yes)
			(layer "B.SilkS")
			(effects
				(font
					(size 0.7874 0.5842)
					(thickness 0.1524)
				)
				(justify left mirror)
			)
		)
		(property "Value" ""
			(at 0 0 0)
			(layer "B.Fab")
			(effects
				(font
					(size 1.27 1.27)
				)
				(justify mirror)
			)
		)
		(duplicate_pad_numbers_are_jumpers no)
		(fp_line
			(start -2.0066 -2.5527)
			(end -2.0066 2.5527)
			(stroke
				(width 0.1524)
				(type default)
			)
			(layer "B.SilkS")
		)
		(fp_line
			(start -2.0066 2.5527)
			(end 2.0066 2.5527)
			(stroke
				(width 0.1524)
				(type default)
			)
			(layer "B.SilkS")
		)
		(fp_line
			(start -0.5715 -2.5527)
			(end -2.0066 -2.5527)
			(stroke
				(width 0.1524)
				(type default)
			)
			(layer "B.SilkS")
		)
		(fp_line
			(start 0 -1.9812)
			(end -0.5715 -2.5527)
			(stroke
				(width 0.1524)
				(type default)
			)
			(layer "B.SilkS")
		)
		(fp_line
			(start 0.5715 -2.5527)
			(end 0 -1.9812)
			(stroke
				(width 0.1524)
				(type default)
			)
			(layer "B.SilkS")
		)
		(fp_line
			(start 2.0066 -2.5527)
			(end 0.5715 -2.5527)
			(stroke
				(width 0.1524)
				(type default)
			)
			(layer "B.SilkS")
		)
		(fp_line
			(start 2.0066 2.5527)
			(end 2.0066 -2.5527)
			(stroke
				(width 0.1524)
				(type default)
			)
			(layer "B.SilkS")
		)
		(fp_poly
			(pts
				(xy 3.793236 -2.006092) (xy 4.346956 -2.33426) (xy 4.346956 -1.70942)
			)
			(stroke
				(width 0)
				(type default)
			)
			(fill yes)
			(layer "B.SilkS")
		)
		(fp_line
			(start -2.249932 -2.549906)
			(end -2.249932 2.549906)
			(stroke
				(width 0.1)
				(type default)
			)
			(layer "B.Fab")
		)
		(fp_line
			(start -2.249932 2.549906)
			(end 2.249932 2.549906)
			(stroke
				(width 0.1)
				(type default)
			)
			(layer "B.Fab")
		)
		(fp_line
			(start 2.249932 -2.549906)
			(end -2.249932 -2.549906)
			(stroke
				(width 0.1)
				(type default)
			)
			(layer "B.Fab")
		)
		(fp_line
			(start 2.249932 2.549906)
			(end 2.249932 -2.549906)
			(stroke
				(width 0.1)
				(type default)
			)
			(layer "B.Fab")
		)
		(fp_poly
			(pts
				(xy 4.36372 -1.608328) (xy 4.36372 -2.233168) (xy 3.81 -1.905)
			)
			(stroke
				(width 0)
				(type default)
			)
			(fill yes)
			(layer "B.Fab")
		)
		(pad "1" smd rect
			(at 2.921 -1.949958 270)
			(size 0.3556 1.4986)
			(layers "B.Cu" "B.Mask" "B.Paste")
			(net "FB_BMC_ISOLATE")
		)
		(pad "2" smd rect
			(at 2.921 -1.299972 270)
			(size 0.3556 1.4986)
			(layers "B.Cu" "B.Mask" "B.Paste")
			(net "NCSI_BMC_RXD1_R")
		)
		(pad "3" smd rect
			(at 2.921 -0.649986 270)
			(size 0.3556 1.4986)
			(layers "B.Cu" "B.Mask" "B.Paste")
			(net "NCSI_OCP_SFF_RXD1")
		)
		(pad "4" smd rect
			(at 2.921 0 270)
			(size 0.3556 1.4986)
			(layers "B.Cu" "B.Mask" "B.Paste")
			(net "FB_BMC_ISOLATE")
		)
		(pad "5" smd rect
			(at 2.921 0.649986 270)
			(size 0.3556 1.4986)
			(layers "B.Cu" "B.Mask" "B.Paste")
			(net "NCSI_BMC_RXD0_R")
		)
		(pad "6" smd rect
			(at 2.921 1.299972 270)
			(size 0.3556 1.4986)
			(layers "B.Cu" "B.Mask" "B.Paste")
			(net "NCSI_OCP_SFF_RXD0")
		)
		(pad "7" smd rect
			(at 2.921 1.949958 270)
			(size 0.3556 1.4986)
			(layers "B.Cu" "B.Mask" "B.Paste")
			(net "GND")
		)
		(pad "8" smd rect
			(at -2.921 1.949958 270)
			(size 0.3556 1.4986)
			(layers "B.Cu" "B.Mask" "B.Paste")
			(net "NCSI_OCP_SFF_CRS_DV")
		)
		(pad "9" smd rect
			(at -2.921 1.299972 270)
			(size 0.3556 1.4986)
			(layers "B.Cu" "B.Mask" "B.Paste")
			(net "NCSI_BMC_CRS_DV_R")
		)
		(pad "10" smd rect
			(at -2.921 0.649986 270)
			(size 0.3556 1.4986)
			(layers "B.Cu" "B.Mask" "B.Paste")
			(net "FB_BMC_ISOLATE")
		)
		(pad "11" smd rect
			(at -2.921 0 270)
			(size 0.3556 1.4986)
			(layers "B.Cu" "B.Mask" "B.Paste")
			(net "OCP_SFF_ISO1_RBT_ARB_IN")
		)
		(pad "12" smd rect
			(at -2.921 -0.649986 270)
			(size 0.3556 1.4986)
			(layers "B.Cu" "B.Mask" "B.Paste")
			(net "OCP_SFF_RBT_ARB_IN_R")
		)
		(pad "13" smd rect
			(at -2.921 -1.299972 270)
			(size 0.3556 1.4986)
			(layers "B.Cu" "B.Mask" "B.Paste")
			(net "FB_BMC_ISOLATE")
		)
		(pad "14" smd rect
			(at -2.921 -1.949958 270)
			(size 0.3556 1.4986)
			(layers "B.Cu" "B.Mask" "B.Paste")
			(net "P3V3_AUX")
		)
	)
)
